#ISCELL
  mstr_symbols cad_note *
  *
#ISCELL
  mstr_symbols design_note *
  *
#ISCELL
  mstr_symbols intel_corp_bpage *
  *
#CELL
  dev_discrete cap_a *
  page132_i1
#ISCELL
  mstr_symbols gnd *
  page132_i10
#CELL
  dev_discrete cap_a *
  page132_i11
#CELL
  dev_discrete cap_a *
  page132_i12
#CELL
  dev_discrete cap_a *
  page132_i13
#ISCELL
  mstr_symbols pvnn_pch_stby *
  page132_i14
#ISCELL
  mstr_symbols gnd *
  page132_i15
#CELL
  dev_discrete cap_a *
  page132_i16
#CELL
  dev_discrete cap_a *
  page132_i17
#ISCELL
  mstr_symbols pvnn_pch_stby *
  page132_i18
#CELL
  dev_discrete cap_a *
  page132_i19
#CELL
  dev_discrete cap_a *
  page132_i2
#CELL
  dev_discrete cap_a *
  page132_i20
#ISCELL
  mstr_symbols gnd *
  page132_i21
#ISCELL
  mstr_symbols pvnn_pch_stby *
  page132_i22
#CELL
  mstr_discrete cap *
  page132_i23
#CELL
  mstr_discrete cap *
  page132_i24
#ISCELL
  mstr_symbols gnd *
  page132_i25
#CELL
  dev_discrete cap_a *
  page132_i26
#CELL
  dev_discrete cap_a *
  page132_i27
#CELL
  dev_discrete cap_a *
  page132_i28
#CELL
  dev_discrete cap_a *
  page132_i29
#CELL
  dev_discrete cap_a *
  page132_i3
#CELL
  dev_discrete cap_a *
  page132_i30
#CELL
  dev_discrete cap_a *
  page132_i31
#CELL
  dev_discrete cap_a *
  page132_i32
#ISCELL
  mstr_symbols gnd *
  page132_i33
#CELL
  dev_discrete cap_a *
  page132_i34
#CELL
  dev_discrete cap_a *
  page132_i35
#CELL
  dev_discrete cap_a *
  page132_i36
#ISCELL
  mstr_symbols gnd *
  page132_i37
#CELL
  mstr_discrete cap *
  page132_i38
#ISCELL
  mstr_symbols pvnn_pch_stby *
  page132_i39
#CELL
  dev_discrete cap_a *
  page132_i4
#CELL
  mstr_discrete cap *
  page132_i40
#ISCELL
  mstr_symbols gnd *
  page132_i41
#CELL
  dev_discrete cap_a *
  page132_i42
#CELL
  dev_discrete cap_a *
  page132_i43
#CELL
  dev_discrete cap_a *
  page132_i44
#CELL
  dev_discrete cap_a *
  page132_i45
#CELL
  dev_discrete cap_a *
  page132_i46
#ISCELL
  mstr_symbols pvnn_pch_stby *
  page132_i47
#CELL
  dev_discrete cap_a *
  page132_i48
#CELL
  dev_discrete cap_a *
  page132_i49
#ISCELL
  mstr_symbols pvnn_pch_stby *
  page132_i5
#ISCELL
  mstr_symbols pvnn_pch_stby *
  page132_i50
#CELL
  dev_discrete cap_a *
  page132_i51
#CELL
  dev_discrete cap_a *
  page132_i52
#ISCELL
  mstr_symbols pvnn_pch_stby *
  page132_i53
#CELL
  dev_discrete cap_a *
  page132_i54
#ISCELL
  mstr_symbols gnd *
  page132_i55
#CELL
  dev_discrete cap_a *
  page132_i56
#CELL
  dev_discrete cap_a *
  page132_i6
#CELL
  dev_discrete cap_a *
  page132_i7
#CELL
  dev_discrete cap_a *
  page132_i8
#CELL
  dev_discrete cap_a *
  page132_i9
